(kicad_sch (version 20230121) (generator eeschema)

  (paper "A3")

  (title_block
    (title "Kria K26 Devboard")
    (date "2024-03-26")
    (rev "1.2.5")
    (comment 1 "www.antmicro.com")
    (comment 2 "Antmicro Ltd.")
  )

  (junction (at 156.845 176.53) (diameter 0) (color 0 0 0 0)
  )
  (junction (at 254 123.825) (diameter 0) (color 0 0 0 0)
  )
  (junction (at 179.07 186.69) (diameter 0) (color 0 0 0 0)
  )
  (junction (at 170.815 176.53) (diameter 0) (color 0 0 0 0)
  )
  (junction (at 239.395 160.02) (diameter 0) (color 0 0 0 0)
  )
  (junction (at 229.235 160.02) (diameter 0) (color 0 0 0 0)
  )
  (junction (at 245.745 123.825) (diameter 0) (color 0 0 0 0)
  )
  (junction (at 168.275 173.99) (diameter 0) (color 0 0 0 0)
  )
  (junction (at 168.275 162.56) (diameter 0) (color 0 0 0 0)
  )
  (junction (at 150.495 173.99) (diameter 0) (color 0 0 0 0)
  )
  (junction (at 262.255 123.825) (diameter 0) (color 0 0 0 0)
  )

  (no_connect (at 215.265 153.67))
  (no_connect (at 180.975 130.81))
  (no_connect (at 215.265 179.07))
  (no_connect (at 215.265 162.56))
  (no_connect (at 215.265 181.61))
  (no_connect (at 180.975 168.91))
  (no_connect (at 215.265 118.11))
  (no_connect (at 215.265 186.69))
  (no_connect (at 180.975 163.83))
  (no_connect (at 215.265 166.37))
  (no_connect (at 215.265 115.57))
  (no_connect (at 215.265 133.35))
  (no_connect (at 215.265 125.73))
  (no_connect (at 180.975 120.65))
  (no_connect (at 180.975 156.21))
  (no_connect (at 215.265 157.48))
  (no_connect (at 215.265 171.45))
  (no_connect (at 180.975 135.89))
  (no_connect (at 180.975 118.11))
  (no_connect (at 180.975 166.37))
  (no_connect (at 180.975 128.27))
  (no_connect (at 215.265 110.49))
  (no_connect (at 215.265 113.03))
  (no_connect (at 215.265 107.95))
  (no_connect (at 215.265 184.15))
  (no_connect (at 180.975 158.75))
  (no_connect (at 215.265 128.27))
  (no_connect (at 180.975 161.29))
  (no_connect (at 215.265 105.41))
  (no_connect (at 215.265 120.65))
  (no_connect (at 215.265 148.59))
  (no_connect (at 180.975 123.19))
  (no_connect (at 215.265 173.99))
  (no_connect (at 215.265 140.97))
  (no_connect (at 215.265 138.43))
  (no_connect (at 215.265 143.51))
  (no_connect (at 215.265 151.13))
  (no_connect (at 180.975 125.73))
  (no_connect (at 215.265 130.81))
  (no_connect (at 180.975 133.35))

  (wire (pts (xy 135.255 176.53) (xy 156.845 176.53))
    (stroke (width 0) (type default))
  )
  (wire (pts (xy 239.395 160.02) (xy 243.205 160.02))
    (stroke (width 0) (type default))
  )
  (wire (pts (xy 254 123.825) (xy 262.255 123.825))
    (stroke (width 0) (type default))
  )
  (wire (pts (xy 262.255 126.365) (xy 262.255 123.825))
    (stroke (width 0) (type default))
  )
  (wire (pts (xy 229.235 150.495) (xy 229.235 152.4))
    (stroke (width 0) (type default))
  )
  (wire (pts (xy 144.145 146.05) (xy 180.975 146.05))
    (stroke (width 0) (type default))
  )
  (wire (pts (xy 179.07 184.15) (xy 180.975 184.15))
    (stroke (width 0) (type default))
  )
  (wire (pts (xy 168.275 162.56) (xy 170.815 162.56))
    (stroke (width 0) (type default))
  )
  (wire (pts (xy 180.975 110.49) (xy 176.53 110.49))
    (stroke (width 0) (type default))
  )
  (wire (pts (xy 193.675 220.98) (xy 191.135 220.98))
    (stroke (width 0) (type default))
  )
  (wire (pts (xy 150.495 172.72) (xy 150.495 173.99))
    (stroke (width 0) (type default))
  )
  (wire (pts (xy 146.685 138.43) (xy 146.685 139.7))
    (stroke (width 0) (type default))
  )
  (wire (pts (xy 160.655 142.24) (xy 160.655 143.51))
    (stroke (width 0) (type default))
  )
  (wire (pts (xy 229.235 160.02) (xy 239.395 160.02))
    (stroke (width 0) (type default))
  )
  (wire (pts (xy 168.275 162.56) (xy 165.735 162.56))
    (stroke (width 0) (type default))
  )
  (wire (pts (xy 239.395 158.75) (xy 239.395 160.02))
    (stroke (width 0) (type default))
  )
  (wire (pts (xy 179.07 186.69) (xy 179.07 187.96))
    (stroke (width 0) (type default))
  )
  (wire (pts (xy 151.765 138.43) (xy 146.685 138.43))
    (stroke (width 0) (type default))
  )
  (wire (pts (xy 229.235 160.02) (xy 229.235 157.48))
    (stroke (width 0) (type default))
  )
  (wire (pts (xy 170.815 171.45) (xy 170.815 176.53))
    (stroke (width 0) (type default))
  )
  (wire (pts (xy 170.815 162.56) (xy 170.815 166.37))
    (stroke (width 0) (type default))
  )
  (wire (pts (xy 160.655 138.43) (xy 160.655 139.7))
    (stroke (width 0) (type default))
  )
  (wire (pts (xy 179.07 186.69) (xy 180.975 186.69))
    (stroke (width 0) (type default))
  )
  (wire (pts (xy 245.745 123.825) (xy 245.745 126.365))
    (stroke (width 0) (type default))
  )
  (wire (pts (xy 146.685 142.24) (xy 146.685 143.51))
    (stroke (width 0) (type default))
  )
  (wire (pts (xy 156.845 176.53) (xy 170.815 176.53))
    (stroke (width 0) (type default))
  )
  (wire (pts (xy 146.685 143.51) (xy 151.765 143.51))
    (stroke (width 0) (type default))
  )
  (wire (pts (xy 160.655 142.24) (xy 180.975 142.24))
    (stroke (width 0) (type default))
  )
  (wire (pts (xy 179.07 184.15) (xy 179.07 186.69))
    (stroke (width 0) (type default))
  )
  (wire (pts (xy 254 123.825) (xy 245.745 123.825))
    (stroke (width 0) (type default))
  )
  (wire (pts (xy 135.255 173.99) (xy 140.335 173.99))
    (stroke (width 0) (type default))
  )
  (wire (pts (xy 168.275 166.37) (xy 168.275 162.56))
    (stroke (width 0) (type default))
  )
  (wire (pts (xy 156.845 172.72) (xy 156.845 176.53))
    (stroke (width 0) (type default))
  )
  (wire (pts (xy 150.495 173.99) (xy 168.275 173.99))
    (stroke (width 0) (type default))
  )
  (wire (pts (xy 180.975 105.41) (xy 176.53 105.41))
    (stroke (width 0) (type default))
  )
  (wire (pts (xy 156.845 138.43) (xy 160.655 138.43))
    (stroke (width 0) (type default))
  )
  (wire (pts (xy 168.275 173.99) (xy 180.975 173.99))
    (stroke (width 0) (type default))
  )
  (wire (pts (xy 145.415 173.99) (xy 150.495 173.99))
    (stroke (width 0) (type default))
  )
  (wire (pts (xy 215.265 160.02) (xy 229.235 160.02))
    (stroke (width 0) (type default))
  )
  (wire (pts (xy 170.815 176.53) (xy 180.975 176.53))
    (stroke (width 0) (type default))
  )
  (wire (pts (xy 144.145 148.59) (xy 180.975 148.59))
    (stroke (width 0) (type default))
  )
  (wire (pts (xy 168.275 171.45) (xy 168.275 173.99))
    (stroke (width 0) (type default))
  )
  (wire (pts (xy 144.145 142.24) (xy 146.685 142.24))
    (stroke (width 0) (type default))
  )
  (wire (pts (xy 144.145 153.67) (xy 180.975 153.67))
    (stroke (width 0) (type default))
  )
  (wire (pts (xy 191.135 220.98) (xy 191.135 222.25))
    (stroke (width 0) (type default))
  )
  (wire (pts (xy 270.51 123.825) (xy 270.51 126.365))
    (stroke (width 0) (type default))
  )
  (wire (pts (xy 144.145 151.13) (xy 180.975 151.13))
    (stroke (width 0) (type default))
  )
  (wire (pts (xy 227.33 150.495) (xy 229.235 150.495))
    (stroke (width 0) (type default))
  )
  (wire (pts (xy 146.685 139.7) (xy 144.145 139.7))
    (stroke (width 0) (type default))
  )
  (wire (pts (xy 245.745 123.825) (xy 241.3 123.825))
    (stroke (width 0) (type default))
  )
  (wire (pts (xy 160.655 139.7) (xy 180.975 139.7))
    (stroke (width 0) (type default))
  )
  (wire (pts (xy 262.255 123.825) (xy 270.51 123.825))
    (stroke (width 0) (type default))
  )
  (wire (pts (xy 176.53 113.03) (xy 180.975 113.03))
    (stroke (width 0) (type default))
  )
  (wire (pts (xy 254 126.365) (xy 254 123.825))
    (stroke (width 0) (type default))
  )
  (wire (pts (xy 160.655 143.51) (xy 156.845 143.51))
    (stroke (width 0) (type default))
  )

  (text "M.2 key E PCIe " (at 182.88 90.17 0)
    (effects (font (size 2.54 2.54) (thickness 0.508) bold) (justify left bottom))
  )
  (text "Mechanical" (at 193.04 215.9 0)
    (effects (font (size 1.27 1.27)) (justify left bottom))
  )

  (label "GTR_DP3_M2C_C_P" (at 161.925 139.7 0) (fields_autoplaced)
    (effects (font (size 1.27 1.27)) (justify left bottom))
  )
  (label "GTR_DP3_M2C_C_N" (at 161.925 142.24 0) (fields_autoplaced)
    (effects (font (size 1.27 1.27)) (justify left bottom))
  )

  (global_label "PS_3V3" (shape input) (at 241.3 123.825 180) (fields_autoplaced)
    (effects (font (size 1.27 1.27)) (justify right))
    (property "Intersheetrefs" "${INTERSHEET_REFS}" (at 199.39 -67.945 0)
      (effects (font (size 1.27 1.27)) (justify left) hide)
    )
  )
  (global_label "PS_3V3" (shape input) (at 227.33 150.495 180) (fields_autoplaced)
    (effects (font (size 1.27 1.27)) (justify right))
    (property "Intersheetrefs" "${INTERSHEET_REFS}" (at 139.7 330.835 0)
      (effects (font (size 1.27 1.27)) hide)
    )
  )
  (global_label "PS_3V3" (shape input) (at 176.53 105.41 180) (fields_autoplaced)
    (effects (font (size 1.27 1.27)) (justify right))
    (property "Intersheetrefs" "${INTERSHEET_REFS}" (at 134.62 -86.36 0)
      (effects (font (size 1.27 1.27)) (justify left) hide)
    )
  )
  (global_label "PS_3V3" (shape input) (at 165.735 162.56 180) (fields_autoplaced)
    (effects (font (size 1.27 1.27)) (justify right))
    (property "Intersheetrefs" "${INTERSHEET_REFS}" (at 59.055 275.59 0)
      (effects (font (size 1.27 1.27)) hide)
    )
  )

  (hierarchical_label "GTR_DP3_M2C_P" (shape input) (at 144.145 139.7 180) (fields_autoplaced)
    (effects (font (size 1.27 1.27)) (justify right))
  )
  (hierarchical_label "GTR_DP3_M2C_N" (shape input) (at 144.145 142.24 180) (fields_autoplaced)
    (effects (font (size 1.27 1.27)) (justify right))
  )
  (hierarchical_label "GTR_DP3_C2M_N" (shape input) (at 144.145 148.59 180) (fields_autoplaced)
    (effects (font (size 1.27 1.27)) (justify right))
  )
  (hierarchical_label "~{M2_PERST}" (shape input) (at 243.205 160.02 0) (fields_autoplaced)
    (effects (font (size 1.27 1.27)) (justify left))
  )
  (hierarchical_label "GTR_REFCLK3_N" (shape input) (at 144.145 153.67 180) (fields_autoplaced)
    (effects (font (size 1.27 1.27)) (justify right))
  )
  (hierarchical_label "GTR_REFCLK3_P" (shape input) (at 144.145 151.13 180) (fields_autoplaced)
    (effects (font (size 1.27 1.27)) (justify right))
  )
  (hierarchical_label "GTR_DP3_C2M_P" (shape input) (at 144.145 146.05 180) (fields_autoplaced)
    (effects (font (size 1.27 1.27)) (justify right))
  )
  (hierarchical_label "~{M2_PEWAKE}" (shape input) (at 135.255 176.53 180) (fields_autoplaced)
    (effects (font (size 1.27 1.27)) (justify right))
  )
  (hierarchical_label "M2_USB_P" (shape input) (at 176.53 110.49 180) (fields_autoplaced)
    (effects (font (size 1.27 1.27)) (justify right))
  )
  (hierarchical_label "~{M2_CLKREQ}" (shape input) (at 135.255 173.99 180) (fields_autoplaced)
    (effects (font (size 1.27 1.27)) (justify right))
  )
  (hierarchical_label "M2_USB_N" (shape input) (at 176.53 113.03 180) (fields_autoplaced)
    (effects (font (size 1.27 1.27)) (justify right))
  )

  (symbol (lib_id "kria-k26-devboard:GND") (at 191.135 222.25 0) (unit 1)
    (in_bom yes) (on_board yes) (dnp no) (fields_autoplaced)
    (property "Reference" "#PWR0397" (at 191.135 228.6 0)
      (effects (font (size 1.27 1.27)) hide)
    )
    (property "Value" "GND" (at 191.135 227.33 0)
      (effects (font (size 1.27 1.27)))
    )
    (property "Footprint" "" (at 200.025 229.87 0)
      (effects (font (size 1.27 1.27) (thickness 0.15)) (justify left bottom) hide)
    )
    (property "Datasheet" "" (at 200.025 234.95 0)
      (effects (font (size 1.27 1.27) (thickness 0.15)) (justify left bottom) hide)
    )
    (property "Author" "Antmicro" (at 200.025 229.87 0)
      (effects (font (size 1.27 1.27) (thickness 0.15)) (justify left bottom) hide)
    )
    (property "License" "Apache-2.0" (at 200.025 232.41 0)
      (effects (font (size 1.27 1.27) (thickness 0.15)) (justify left bottom) hide)
    )
    (pin "1")
    (instances
      (project "kria-k26-devboard"
        (path ""
          (reference "#PWR0397") (unit 1)
        )
      )
    )
  )

  (symbol (lib_id "kria-k26-devboard:Spacer_Drill3mm_H1.5mm_9774015243R") (at 193.675 220.98 0) (unit 1)
    (in_bom yes) (on_board yes) (dnp no) (fields_autoplaced)
    (property "Reference" "SP5" (at 202.565 219.71 0)
      (effects (font (size 1.524 1.524)) (justify left))
    )
    (property "Value" "Spacer_H1.5mm_9774015243R" (at 202.565 222.8849 0)
      (effects (font (size 1.27 1.27) (thickness 0.15)) (justify left) hide)
    )
    (property "Footprint" "kria-k26-devboard-footprints:Spacer_Drill3mm_H1.5mm_9774015243R" (at 216.535 228.6 0)
      (effects (font (size 1.27 1.27) (thickness 0.15)) (justify left bottom) hide)
    )
    (property "Datasheet" "https://www.we-online.com/catalog/datasheet/9774015243R.pdf" (at 216.535 231.14 0)
      (effects (font (size 1.27 1.27) (thickness 0.15)) (justify left bottom) hide)
    )
    (property "Manufacturer" "Würth Elektronik" (at 216.535 233.68 0)
      (effects (font (size 1.27 1.27) (thickness 0.15)) (justify left bottom) hide)
    )
    (property "MPN" "9774015243R" (at 202.565 222.8849 0)
      (effects (font (size 1.27 1.27) (thickness 0.15)) (justify left))
    )
    (property "Author" "Antmicro" (at 216.535 238.76 0)
      (effects (font (size 1.27 1.27) (thickness 0.15)) (justify left bottom) hide)
    )
    (property "License" "Apache-2.0" (at 216.535 241.3 0)
      (effects (font (size 1.27 1.27) (thickness 0.15)) (justify left bottom) hide)
    )
    (pin "1")
    (instances
      (project "kria-k26-devboard"
        (path ""
          (reference "SP5") (unit 1)
        )
      )
    )
  )

  (symbol (lib_id "kria-k26-devboard:TP_0.75mm_SMD") (at 239.395 158.75 90) (unit 1)
    (in_bom yes) (on_board yes) (dnp no)
    (property "Reference" "TP49" (at 237.49 153.67 90)
      (effects (font (size 1.27 1.27)) (justify right))
    )
    (property "Value" "TP_0.75mm_SMD" (at 247.015 140.97 0)
      (effects (font (size 1.27 1.27) (thickness 0.15)) (justify left bottom) hide)
    )
    (property "Footprint" "kria-k26-devboard-footprints:TP_SMD_0.75mm" (at 249.555 140.97 0)
      (effects (font (size 1.27 1.27) (thickness 0.15)) (justify left bottom) hide)
    )
    (property "Datasheet" "" (at 252.095 140.97 0)
      (effects (font (size 1.27 1.27) (thickness 0.15)) (justify left bottom) hide)
    )
    (property "MPN" "" (at 254.635 140.97 0)
      (effects (font (size 1.27 1.27) (thickness 0.15)) (justify left bottom) hide)
    )
    (property "Manufacturer" "" (at 257.175 140.97 0)
      (effects (font (size 1.27 1.27) (thickness 0.15)) (justify left bottom) hide)
    )
    (property "Author" "Antmicro" (at 259.715 140.97 0)
      (effects (font (size 1.27 1.27) (thickness 0.15)) (justify left bottom) hide)
    )
    (property "License" "Apache-2.0" (at 262.255 140.97 0)
      (effects (font (size 1.27 1.27) (thickness 0.15)) (justify left bottom) hide)
    )
    (pin "1")
    (instances
      (project "kria-k26-devboard"
        (path ""
          (reference "TP49") (unit 1)
        )
      )
    )
  )

  (symbol (lib_id "kria-k26-devboard:TP_0.75mm_SMD") (at 156.845 172.72 90) (unit 1)
    (in_bom yes) (on_board yes) (dnp no)
    (property "Reference" "TP48" (at 154.305 167.64 90)
      (effects (font (size 1.27 1.27)) (justify right))
    )
    (property "Value" "TP_0.75mm_SMD" (at 164.465 154.94 0)
      (effects (font (size 1.27 1.27) (thickness 0.15)) (justify left bottom) hide)
    )
    (property "Footprint" "kria-k26-devboard-footprints:TP_SMD_0.75mm" (at 167.005 154.94 0)
      (effects (font (size 1.27 1.27) (thickness 0.15)) (justify left bottom) hide)
    )
    (property "Datasheet" "" (at 169.545 154.94 0)
      (effects (font (size 1.27 1.27) (thickness 0.15)) (justify left bottom) hide)
    )
    (property "MPN" "" (at 172.085 154.94 0)
      (effects (font (size 1.27 1.27) (thickness 0.15)) (justify left bottom) hide)
    )
    (property "Manufacturer" "" (at 174.625 154.94 0)
      (effects (font (size 1.27 1.27) (thickness 0.15)) (justify left bottom) hide)
    )
    (property "Author" "Antmicro" (at 177.165 154.94 0)
      (effects (font (size 1.27 1.27) (thickness 0.15)) (justify left bottom) hide)
    )
    (property "License" "Apache-2.0" (at 179.705 154.94 0)
      (effects (font (size 1.27 1.27) (thickness 0.15)) (justify left bottom) hide)
    )
    (pin "1")
    (instances
      (project "kria-k26-devboard"
        (path ""
          (reference "TP48") (unit 1)
        )
      )
    )
  )

  (symbol (lib_id "kria-k26-devboard:TP_0.75mm_SMD") (at 150.495 172.72 270) (mirror x) (unit 1)
    (in_bom yes) (on_board yes) (dnp no)
    (property "Reference" "TP47" (at 153.035 167.64 90)
      (effects (font (size 1.27 1.27)) (justify right))
    )
    (property "Value" "TP_0.75mm_SMD" (at 142.875 154.94 0)
      (effects (font (size 1.27 1.27) (thickness 0.15)) (justify left bottom) hide)
    )
    (property "Footprint" "kria-k26-devboard-footprints:TP_SMD_0.75mm" (at 140.335 154.94 0)
      (effects (font (size 1.27 1.27) (thickness 0.15)) (justify left bottom) hide)
    )
    (property "Datasheet" "" (at 137.795 154.94 0)
      (effects (font (size 1.27 1.27) (thickness 0.15)) (justify left bottom) hide)
    )
    (property "MPN" "" (at 135.255 154.94 0)
      (effects (font (size 1.27 1.27) (thickness 0.15)) (justify left bottom) hide)
    )
    (property "Manufacturer" "" (at 132.715 154.94 0)
      (effects (font (size 1.27 1.27) (thickness 0.15)) (justify left bottom) hide)
    )
    (property "Author" "Antmicro" (at 130.175 154.94 0)
      (effects (font (size 1.27 1.27) (thickness 0.15)) (justify left bottom) hide)
    )
    (property "License" "Apache-2.0" (at 127.635 154.94 0)
      (effects (font (size 1.27 1.27) (thickness 0.15)) (justify left bottom) hide)
    )
    (pin "1")
    (instances
      (project "kria-k26-devboard"
        (path ""
          (reference "TP47") (unit 1)
        )
      )
    )
  )

  (symbol (lib_id "kria-k26-devboard:R_0R_0402") (at 140.335 173.99 0) (unit 1)
    (in_bom yes) (on_board yes) (dnp no) (fields_autoplaced)
    (property "Reference" "R150" (at 142.875 167.64 0)
      (effects (font (size 1.524 1.524)))
    )
    (property "Value" "R_0R_0402" (at 160.655 186.69 0)
      (effects (font (size 1.27 1.27) (thickness 0.15)) (justify left bottom) hide)
    )
    (property "Footprint" "kria-k26-devboard-footprints:R_0402_1005Metric" (at 160.655 189.23 0)
      (effects (font (size 1.27 1.27) (thickness 0.15)) (justify left bottom) hide)
    )
    (property "Datasheet" "https://industrial.panasonic.com/cdbs/www-data/pdf/RDA0000/AOA0000C301.pdf" (at 160.655 191.77 0)
      (effects (font (size 1.27 1.27) (thickness 0.15)) (justify left bottom) hide)
    )
    (property "Manufacturer" "Panasonic" (at 160.655 196.85 0)
      (effects (font (size 1.27 1.27) (thickness 0.15)) (justify left bottom) hide)
    )
    (property "MPN" "ERJ2GE0R00X" (at 160.655 194.31 0)
      (effects (font (size 1.27 1.27) (thickness 0.15)) (justify left bottom) hide)
    )
    (property "Val" "0R" (at 142.875 170.18 0)
      (effects (font (size 1.27 1.27) (thickness 0.15)))
    )
    (property "License" "Apache-2.0" (at 160.655 199.39 0)
      (effects (font (size 1.27 1.27) (thickness 0.15)) (justify left bottom) hide)
    )
    (property "Author" "Antmicro" (at 160.655 201.93 0)
      (effects (font (size 1.27 1.27) (thickness 0.15)) (justify left bottom) hide)
    )
    (property "Tolerance" "~" (at 160.655 184.15 0)
      (effects (font (size 1.27 1.27)) (justify left bottom) hide)
    )
    (property "Current" "1A" (at 160.655 204.47 0)
      (effects (font (size 1.27 1.27) (thickness 0.15)) (justify left bottom) hide)
    )
    (pin "1")
    (pin "2")
    (instances
      (project "kria-k26-devboard"
        (path ""
          (reference "R150") (unit 1)
        )
      )
    )
  )

  (symbol (lib_id "kria-k26-devboard:GND") (at 179.07 187.96 0) (unit 1)
    (in_bom yes) (on_board yes) (dnp no) (fields_autoplaced)
    (property "Reference" "#PWR0398" (at 179.07 194.31 0)
      (effects (font (size 1.27 1.27)) hide)
    )
    (property "Value" "GND" (at 179.07 193.04 0)
      (effects (font (size 1.27 1.27)))
    )
    (property "Footprint" "" (at 187.96 195.58 0)
      (effects (font (size 1.27 1.27) (thickness 0.15)) (justify left bottom) hide)
    )
    (property "Datasheet" "" (at 187.96 200.66 0)
      (effects (font (size 1.27 1.27) (thickness 0.15)) (justify left bottom) hide)
    )
    (property "Author" "Antmicro" (at 187.96 195.58 0)
      (effects (font (size 1.27 1.27) (thickness 0.15)) (justify left bottom) hide)
    )
    (property "License" "Apache-2.0" (at 187.96 198.12 0)
      (effects (font (size 1.27 1.27) (thickness 0.15)) (justify left bottom) hide)
    )
    (pin "1")
    (instances
      (project "kria-k26-devboard"
        (path ""
          (reference "#PWR0398") (unit 1)
        )
      )
    )
  )

  (symbol (lib_id "kria-k26-devboard:C_100n_0402") (at 151.765 138.43 0) (unit 1)
    (in_bom yes) (on_board yes) (dnp no)
    (property "Reference" "C233" (at 150.495 137.16 0)
      (effects (font (size 1.524 1.524)))
    )
    (property "Value" "C_100n_0402" (at 172.085 148.59 0)
      (effects (font (size 1.27 1.27) (thickness 0.15)) (justify left bottom) hide)
    )
    (property "Footprint" "kria-k26-devboard-footprints:C_0402_1005Metric" (at 172.085 151.13 0)
      (effects (font (size 1.27 1.27) (thickness 0.15)) (justify left bottom) hide)
    )
    (property "Datasheet" "https://search.murata.co.jp/Ceramy/image/img/A01X/G101/ENG/GRM155R61H104KE14-01.pdf" (at 172.085 153.67 0)
      (effects (font (size 1.27 1.27) (thickness 0.15)) (justify left bottom) hide)
    )
    (property "Manufacturer" "Murata" (at 172.085 158.75 0)
      (effects (font (size 1.27 1.27) (thickness 0.15)) (justify left bottom) hide)
    )
    (property "MPN" "GRM155R61H104KE14D" (at 172.085 156.21 0)
      (effects (font (size 1.27 1.27) (thickness 0.15)) (justify left bottom) hide)
    )
    (property "Val" "100n" (at 157.48 137.16 0)
      (effects (font (size 1.27 1.27) (thickness 0.15)))
    )
    (property "License" "Apache-2.0" (at 172.085 161.29 0)
      (effects (font (size 1.27 1.27) (thickness 0.15)) (justify left bottom) hide)
    )
    (property "Author" "Antmicro" (at 172.085 163.83 0)
      (effects (font (size 1.27 1.27) (thickness 0.15)) (justify left bottom) hide)
    )
    (property "Voltage" "50V" (at 172.085 166.37 0)
      (effects (font (size 1.27 1.27)) (justify left bottom) hide)
    )
    (property "Dielectric" "X5R" (at 172.085 168.91 0)
      (effects (font (size 1.27 1.27)) (justify left bottom) hide)
    )
    (pin "1")
    (pin "2")
    (instances
      (project "kria-k26-devboard"
        (path ""
          (reference "C233") (unit 1)
        )
      )
    )
  )

  (symbol (lib_id "kria-k26-devboard:C_100n_0402") (at 151.765 143.51 0) (mirror x) (unit 1)
    (in_bom yes) (on_board yes) (dnp no)
    (property "Reference" "C234" (at 147.32 142.24 0)
      (effects (font (size 1.524 1.524)) (justify left))
    )
    (property "Value" "C_100n_0402" (at 172.085 133.35 0)
      (effects (font (size 1.27 1.27) (thickness 0.15)) (justify left bottom) hide)
    )
    (property "Footprint" "kria-k26-devboard-footprints:C_0402_1005Metric" (at 172.085 130.81 0)
      (effects (font (size 1.27 1.27) (thickness 0.15)) (justify left bottom) hide)
    )
    (property "Datasheet" "https://search.murata.co.jp/Ceramy/image/img/A01X/G101/ENG/GRM155R61H104KE14-01.pdf" (at 172.085 128.27 0)
      (effects (font (size 1.27 1.27) (thickness 0.15)) (justify left bottom) hide)
    )
    (property "Manufacturer" "Murata" (at 172.085 123.19 0)
      (effects (font (size 1.27 1.27) (thickness 0.15)) (justify left bottom) hide)
    )
    (property "MPN" "GRM155R61H104KE14D" (at 172.085 125.73 0)
      (effects (font (size 1.27 1.27) (thickness 0.15)) (justify left bottom) hide)
    )
    (property "Val" "100n" (at 154.94 142.24 0)
      (effects (font (size 1.27 1.27) (thickness 0.15)) (justify left))
    )
    (property "License" "Apache-2.0" (at 172.085 120.65 0)
      (effects (font (size 1.27 1.27) (thickness 0.15)) (justify left bottom) hide)
    )
    (property "Author" "Antmicro" (at 172.085 118.11 0)
      (effects (font (size 1.27 1.27) (thickness 0.15)) (justify left bottom) hide)
    )
    (property "Voltage" "50V" (at 172.085 115.57 0)
      (effects (font (size 1.27 1.27)) (justify left bottom) hide)
    )
    (property "Dielectric" "X5R" (at 172.085 113.03 0)
      (effects (font (size 1.27 1.27)) (justify left bottom) hide)
    )
    (pin "1")
    (pin "2")
    (instances
      (project "kria-k26-devboard"
        (path ""
          (reference "C234") (unit 1)
        )
      )
    )
  )

  (symbol (lib_id "kria-k26-devboard:C_10u_0603") (at 245.745 126.365 90) (mirror x) (unit 1)
    (in_bom yes) (on_board yes) (dnp no)
    (property "Reference" "C237" (at 246.38 127 90)
      (effects (font (size 1.524 1.524)) (justify right))
    )
    (property "Value" "C_10u_0603" (at 255.905 146.685 0)
      (effects (font (size 1.27 1.27) (thickness 0.15)) (justify left bottom) hide)
    )
    (property "Footprint" "kria-k26-devboard-footprints:C_0603_1608Metric" (at 258.445 146.685 0)
      (effects (font (size 1.27 1.27) (thickness 0.15)) (justify left bottom) hide)
    )
    (property "Datasheet" " " (at 260.985 146.685 0)
      (effects (font (size 1.27 1.27) (thickness 0.15)) (justify left bottom) hide)
    )
    (property "Manufacturer" "Murata" (at 266.065 146.685 0)
      (effects (font (size 1.27 1.27) (thickness 0.15)) (justify left bottom) hide)
    )
    (property "MPN" "GRM188R61A106KE69D" (at 263.525 146.685 0)
      (effects (font (size 1.27 1.27) (thickness 0.15)) (justify left bottom) hide)
    )
    (property "Val" "10u" (at 246.38 130.81 90)
      (effects (font (size 1.27 1.27) (thickness 0.15)) (justify right))
    )
    (property "License" "Apache-2.0" (at 268.605 146.685 0)
      (effects (font (size 1.27 1.27) (thickness 0.15)) (justify left bottom) hide)
    )
    (property "Author" "Antmicro" (at 271.145 146.685 0)
      (effects (font (size 1.27 1.27) (thickness 0.15)) (justify left bottom) hide)
    )
    (property "Voltage" "" (at 273.685 146.685 0)
      (effects (font (size 1.27 1.27)) (justify left bottom) hide)
    )
    (pin "1")
    (pin "2")
    (instances
      (project "kria-k26-devboard"
        (path ""
          (reference "C237") (unit 1)
        )
      )
    )
  )

  (symbol (lib_id "kria-k26-devboard:R_10k_0402") (at 170.815 166.37 270) (unit 1)
    (in_bom yes) (on_board yes) (dnp no) (fields_autoplaced)
    (property "Reference" "R152" (at 173.355 167.64 90)
      (effects (font (size 1.524 1.524)) (justify left))
    )
    (property "Value" "R_10k_0402" (at 158.115 186.69 0)
      (effects (font (size 1.27 1.27) (thickness 0.15)) (justify left bottom) hide)
    )
    (property "Footprint" "kria-k26-devboard-footprints:R_0402_1005Metric" (at 155.575 186.69 0)
      (effects (font (size 1.27 1.27) (thickness 0.15)) (justify left bottom) hide)
    )
    (property "Datasheet" "https://www.bourns.com/docs/product-datasheets/cr.pdf" (at 153.035 186.69 0)
      (effects (font (size 1.27 1.27) (thickness 0.15)) (justify left bottom) hide)
    )
    (property "Manufacturer" "Bourns" (at 147.955 186.69 0)
      (effects (font (size 1.27 1.27) (thickness 0.15)) (justify left bottom) hide)
    )
    (property "MPN" "CR0402-FX-1002GLF" (at 150.495 186.69 0)
      (effects (font (size 1.27 1.27) (thickness 0.15)) (justify left bottom) hide)
    )
    (property "Val" "10k" (at 173.355 170.8149 90)
      (effects (font (size 1.27 1.27) (thickness 0.15)) (justify left))
    )
    (property "License" "Apache-2.0" (at 145.415 186.69 0)
      (effects (font (size 1.27 1.27) (thickness 0.15)) (justify left bottom) hide)
    )
    (property "Author" "Antmicro" (at 142.875 186.69 0)
      (effects (font (size 1.27 1.27) (thickness 0.15)) (justify left bottom) hide)
    )
    (property "Tolerance" "1%" (at 160.655 186.69 0)
      (effects (font (size 1.27 1.27)) (justify left bottom) hide)
    )
    (pin "1")
    (pin "2")
    (instances
      (project "kria-k26-devboard"
        (path ""
          (reference "R152") (unit 1)
        )
      )
    )
  )

  (symbol (lib_id "kria-k26-devboard:R_10k_0402") (at 168.275 166.37 90) (mirror x) (unit 1)
    (in_bom yes) (on_board yes) (dnp no) (fields_autoplaced)
    (property "Reference" "R151" (at 165.735 167.64 90)
      (effects (font (size 1.524 1.524)) (justify left))
    )
    (property "Value" "R_10k_0402" (at 180.975 186.69 0)
      (effects (font (size 1.27 1.27) (thickness 0.15)) (justify left bottom) hide)
    )
    (property "Footprint" "kria-k26-devboard-footprints:R_0402_1005Metric" (at 183.515 186.69 0)
      (effects (font (size 1.27 1.27) (thickness 0.15)) (justify left bottom) hide)
    )
    (property "Datasheet" "https://www.bourns.com/docs/product-datasheets/cr.pdf" (at 186.055 186.69 0)
      (effects (font (size 1.27 1.27) (thickness 0.15)) (justify left bottom) hide)
    )
    (property "Manufacturer" "Bourns" (at 191.135 186.69 0)
      (effects (font (size 1.27 1.27) (thickness 0.15)) (justify left bottom) hide)
    )
    (property "MPN" "CR0402-FX-1002GLF" (at 188.595 186.69 0)
      (effects (font (size 1.27 1.27) (thickness 0.15)) (justify left bottom) hide)
    )
    (property "Val" "10k" (at 165.735 170.8149 90)
      (effects (font (size 1.27 1.27) (thickness 0.15)) (justify left))
    )
    (property "License" "Apache-2.0" (at 193.675 186.69 0)
      (effects (font (size 1.27 1.27) (thickness 0.15)) (justify left bottom) hide)
    )
    (property "Author" "Antmicro" (at 196.215 186.69 0)
      (effects (font (size 1.27 1.27) (thickness 0.15)) (justify left bottom) hide)
    )
    (property "Tolerance" "1%" (at 178.435 186.69 0)
      (effects (font (size 1.27 1.27)) (justify left bottom) hide)
    )
    (pin "1")
    (pin "2")
    (instances
      (project "kria-k26-devboard"
        (path ""
          (reference "R151") (unit 1)
        )
      )
    )
  )

  (symbol (lib_id "kria-k26-devboard:R_10k_0402") (at 229.235 152.4 270) (unit 1)
    (in_bom yes) (on_board yes) (dnp no)
    (property "Reference" "R153" (at 231.14 153.6701 90)
      (effects (font (size 1.524 1.524)) (justify left))
    )
    (property "Value" "R_10k_0402" (at 216.535 172.72 0)
      (effects (font (size 1.27 1.27) (thickness 0.15)) (justify left bottom) hide)
    )
    (property "Footprint" "kria-k26-devboard-footprints:R_0402_1005Metric" (at 213.995 172.72 0)
      (effects (font (size 1.27 1.27) (thickness 0.15)) (justify left bottom) hide)
    )
    (property "Datasheet" "https://www.bourns.com/docs/product-datasheets/cr.pdf" (at 211.455 172.72 0)
      (effects (font (size 1.27 1.27) (thickness 0.15)) (justify left bottom) hide)
    )
    (property "Manufacturer" "Bourns" (at 206.375 172.72 0)
      (effects (font (size 1.27 1.27) (thickness 0.15)) (justify left bottom) hide)
    )
    (property "MPN" "CR0402-FX-1002GLF" (at 208.915 172.72 0)
      (effects (font (size 1.27 1.27) (thickness 0.15)) (justify left bottom) hide)
    )
    (property "Val" "10k" (at 231.14 156.845 90)
      (effects (font (size 1.27 1.27) (thickness 0.15)) (justify left))
    )
    (property "License" "Apache-2.0" (at 203.835 172.72 0)
      (effects (font (size 1.27 1.27) (thickness 0.15)) (justify left bottom) hide)
    )
    (property "Author" "Antmicro" (at 201.295 172.72 0)
      (effects (font (size 1.27 1.27) (thickness 0.15)) (justify left bottom) hide)
    )
    (property "Tolerance" "1%" (at 219.075 172.72 0)
      (effects (font (size 1.27 1.27)) (justify left bottom) hide)
    )
    (pin "1")
    (pin "2")
    (instances
      (project "kria-k26-devboard"
        (path ""
          (reference "R153") (unit 1)
        )
      )
    )
  )

  (symbol (lib_id "kria-k26-devboard:GND") (at 254 131.445 0) (mirror y) (unit 1)
    (in_bom yes) (on_board yes) (dnp no) (fields_autoplaced)
    (property "Reference" "#PWR0400" (at 254 137.795 0)
      (effects (font (size 1.27 1.27)) hide)
    )
    (property "Value" "GND" (at 254 136.525 0)
      (effects (font (size 1.27 1.27)))
    )
    (property "Footprint" "" (at 245.11 139.065 0)
      (effects (font (size 1.27 1.27) (thickness 0.15)) (justify left bottom) hide)
    )
    (property "Datasheet" "" (at 245.11 144.145 0)
      (effects (font (size 1.27 1.27) (thickness 0.15)) (justify left bottom) hide)
    )
    (property "Author" "Antmicro" (at 245.11 139.065 0)
      (effects (font (size 1.27 1.27) (thickness 0.15)) (justify left bottom) hide)
    )
    (property "License" "Apache-2.0" (at 245.11 141.605 0)
      (effects (font (size 1.27 1.27) (thickness 0.15)) (justify left bottom) hide)
    )
    (pin "1")
    (instances
      (project "kria-k26-devboard"
        (path ""
          (reference "#PWR0400") (unit 1)
        )
      )
    )
  )

  (symbol (lib_id "kria-k26-devboard:C_100n_0402") (at 254 126.365 90) (mirror x) (unit 1)
    (in_bom yes) (on_board yes) (dnp no)
    (property "Reference" "C235" (at 254.635 127 90)
      (effects (font (size 1.524 1.524)) (justify right))
    )
    (property "Value" "C_100n_0402" (at 264.16 146.685 0)
      (effects (font (size 1.27 1.27) (thickness 0.15)) (justify left bottom) hide)
    )
    (property "Footprint" "kria-k26-devboard-footprints:C_0402_1005Metric" (at 266.7 146.685 0)
      (effects (font (size 1.27 1.27) (thickness 0.15)) (justify left bottom) hide)
    )
    (property "Datasheet" "https://search.murata.co.jp/Ceramy/image/img/A01X/G101/ENG/GRM155R61H104KE14-01.pdf" (at 269.24 146.685 0)
      (effects (font (size 1.27 1.27) (thickness 0.15)) (justify left bottom) hide)
    )
    (property "Manufacturer" "Murata" (at 274.32 146.685 0)
      (effects (font (size 1.27 1.27) (thickness 0.15)) (justify left bottom) hide)
    )
    (property "MPN" "GRM155R61H104KE14D" (at 271.78 146.685 0)
      (effects (font (size 1.27 1.27) (thickness 0.15)) (justify left bottom) hide)
    )
    (property "Val" "100n" (at 254.635 130.81 90)
      (effects (font (size 1.27 1.27) (thickness 0.15)) (justify right))
    )
    (property "License" "Apache-2.0" (at 276.86 146.685 0)
      (effects (font (size 1.27 1.27) (thickness 0.15)) (justify left bottom) hide)
    )
    (property "Author" "Antmicro" (at 279.4 146.685 0)
      (effects (font (size 1.27 1.27) (thickness 0.15)) (justify left bottom) hide)
    )
    (property "Voltage" "50V" (at 281.94 146.685 0)
      (effects (font (size 1.27 1.27)) (justify left bottom) hide)
    )
    (property "Dielectric" "X5R" (at 284.48 146.685 0)
      (effects (font (size 1.27 1.27)) (justify left bottom) hide)
    )
    (pin "1")
    (pin "2")
    (instances
      (project "kria-k26-devboard"
        (path ""
          (reference "C235") (unit 1)
        )
      )
    )
  )

  (symbol (lib_id "kria-k26-devboard:C_10u_0603") (at 270.51 126.365 270) (unit 1)
    (in_bom yes) (on_board yes) (dnp no) (fields_autoplaced)
    (property "Reference" "C238" (at 273.685 127.6413 90)
      (effects (font (size 1.524 1.524)) (justify left))
    )
    (property "Value" "C_10u_0603" (at 260.35 146.685 0)
      (effects (font (size 1.27 1.27) (thickness 0.15)) (justify left bottom) hide)
    )
    (property "Footprint" "kria-k26-devboard-footprints:C_0603_1608Metric" (at 257.81 146.685 0)
      (effects (font (size 1.27 1.27) (thickness 0.15)) (justify left bottom) hide)
    )
    (property "Datasheet" " " (at 255.27 146.685 0)
      (effects (font (size 1.27 1.27) (thickness 0.15)) (justify left bottom) hide)
    )
    (property "Manufacturer" "Murata" (at 250.19 146.685 0)
      (effects (font (size 1.27 1.27) (thickness 0.15)) (justify left bottom) hide)
    )
    (property "MPN" "GRM188R61A106KE69D" (at 252.73 146.685 0)
      (effects (font (size 1.27 1.27) (thickness 0.15)) (justify left bottom) hide)
    )
    (property "Val" "10u" (at 273.685 130.8162 90)
      (effects (font (size 1.27 1.27) (thickness 0.15)) (justify left))
    )
    (property "License" "Apache-2.0" (at 247.65 146.685 0)
      (effects (font (size 1.27 1.27) (thickness 0.15)) (justify left bottom) hide)
    )
    (property "Author" "Antmicro" (at 245.11 146.685 0)
      (effects (font (size 1.27 1.27) (thickness 0.15)) (justify left bottom) hide)
    )
    (property "Voltage" "" (at 242.57 146.685 0)
      (effects (font (size 1.27 1.27)) (justify left bottom) hide)
    )
    (pin "1")
    (pin "2")
    (instances
      (project "kria-k26-devboard"
        (path ""
          (reference "C238") (unit 1)
        )
      )
    )
  )

  (symbol (lib_id "kria-k26-devboard:C_100n_0402") (at 262.255 126.365 270) (unit 1)
    (in_bom yes) (on_board yes) (dnp no)
    (property "Reference" "C236" (at 262.89 127 90)
      (effects (font (size 1.524 1.524)) (justify left))
    )
    (property "Value" "C_100n_0402" (at 252.095 146.685 0)
      (effects (font (size 1.27 1.27) (thickness 0.15)) (justify left bottom) hide)
    )
    (property "Footprint" "kria-k26-devboard-footprints:C_0402_1005Metric" (at 249.555 146.685 0)
      (effects (font (size 1.27 1.27) (thickness 0.15)) (justify left bottom) hide)
    )
    (property "Datasheet" "https://search.murata.co.jp/Ceramy/image/img/A01X/G101/ENG/GRM155R61H104KE14-01.pdf" (at 247.015 146.685 0)
      (effects (font (size 1.27 1.27) (thickness 0.15)) (justify left bottom) hide)
    )
    (property "Manufacturer" "Murata" (at 241.935 146.685 0)
      (effects (font (size 1.27 1.27) (thickness 0.15)) (justify left bottom) hide)
    )
    (property "MPN" "GRM155R61H104KE14D" (at 244.475 146.685 0)
      (effects (font (size 1.27 1.27) (thickness 0.15)) (justify left bottom) hide)
    )
    (property "Val" "100n" (at 262.89 130.81 90)
      (effects (font (size 1.27 1.27) (thickness 0.15)) (justify left))
    )
    (property "License" "Apache-2.0" (at 239.395 146.685 0)
      (effects (font (size 1.27 1.27) (thickness 0.15)) (justify left bottom) hide)
    )
    (property "Author" "Antmicro" (at 236.855 146.685 0)
      (effects (font (size 1.27 1.27) (thickness 0.15)) (justify left bottom) hide)
    )
    (property "Voltage" "50V" (at 234.315 146.685 0)
      (effects (font (size 1.27 1.27)) (justify left bottom) hide)
    )
    (property "Dielectric" "X5R" (at 231.775 146.685 0)
      (effects (font (size 1.27 1.27)) (justify left bottom) hide)
    )
    (pin "1")
    (pin "2")
    (instances
      (project "kria-k26-devboard"
        (path ""
          (reference "C236") (unit 1)
        )
      )
    )
  )

  (symbol (lib_id "kria-k26-devboard:Bus_M.2_2199119-6") (at 180.975 105.41 0) (unit 1)
    (in_bom yes) (on_board yes) (dnp no) (fields_autoplaced)
    (property "Reference" "J12" (at 198.12 97.79 0)
      (effects (font (size 1.27 1.27)))
    )
    (property "Value" "Bus_M.2_2199119-6" (at 229.235 110.49 0)
      (effects (font (size 1.27 1.27) (thickness 0.15)) (justify left bottom) hide)
    )
    (property "Footprint" "kria-k26-devboard-footprints:Bus_M.2_Socket_Key_E_TE_1-2199119-6" (at 229.235 113.03 0)
      (effects (font (size 1.27 1.27) (thickness 0.15)) (justify left bottom) hide)
    )
    (property "Datasheet" "https://www.te.com/usa-en/product-1-2199119-6.datasheet.pdf" (at 229.235 115.57 0)
      (effects (font (size 1.27 1.27) (thickness 0.15)) (justify left bottom) hide)
    )
    (property "MPN" "2199119-6" (at 198.12 100.33 0)
      (effects (font (size 1.27 1.27) (thickness 0.15)))
    )
    (property "Manufacturer" "TE Connectivity" (at 229.235 120.65 0)
      (effects (font (size 1.27 1.27) (thickness 0.15)) (justify left bottom) hide)
    )
    (property "Author" "Antmicro" (at 229.235 123.19 0)
      (effects (font (size 1.27 1.27) (thickness 0.15)) (justify left bottom) hide)
    )
    (property "License" "Apache-2.0" (at 229.235 125.73 0)
      (effects (font (size 1.27 1.27) (thickness 0.15)) (justify left bottom) hide)
    )
    (pin "1")
    (pin "10")
    (pin "11")
    (pin "12")
    (pin "13")
    (pin "14")
    (pin "15")
    (pin "16")
    (pin "17")
    (pin "18")
    (pin "19")
    (pin "2")
    (pin "20")
    (pin "21")
    (pin "22")
    (pin "23")
    (pin "3")
    (pin "32")
    (pin "33")
    (pin "34")
    (pin "35")
    (pin "36")
    (pin "37")
    (pin "38")
    (pin "39")
    (pin "4")
    (pin "40")
    (pin "41")
    (pin "42")
    (pin "43")
    (pin "44")
    (pin "45")
    (pin "46")
    (pin "47")
    (pin "48")
    (pin "49")
    (pin "5")
    (pin "50")
    (pin "51")
    (pin "52")
    (pin "53")
    (pin "54")
    (pin "55")
    (pin "56")
    (pin "57")
    (pin "58")
    (pin "59")
    (pin "6")
    (pin "60")
    (pin "61")
    (pin "62")
    (pin "63")
    (pin "64")
    (pin "65")
    (pin "66")
    (pin "67")
    (pin "68")
    (pin "69")
    (pin "7")
    (pin "70")
    (pin "71")
    (pin "72")
    (pin "73")
    (pin "74")
    (pin "75")
    (pin "8")
    (pin "9")
    (pin "MP")
    (instances
      (project "kria-k26-devboard"
        (path ""
          (reference "J12") (unit 1)
        )
      )
    )
  )

  (symbol (lib_id "kria-k26-devboard:GND") (at 270.51 131.445 0) (mirror y) (unit 1)
    (in_bom yes) (on_board yes) (dnp no) (fields_autoplaced)
    (property "Reference" "#PWR0337" (at 270.51 137.795 0)
      (effects (font (size 1.27 1.27)) hide)
    )
    (property "Value" "GND" (at 270.51 136.525 0)
      (effects (font (size 1.27 1.27)))
    )
    (property "Footprint" "" (at 261.62 139.065 0)
      (effects (font (size 1.27 1.27) (thickness 0.15)) (justify left bottom) hide)
    )
    (property "Datasheet" "" (at 261.62 144.145 0)
      (effects (font (size 1.27 1.27) (thickness 0.15)) (justify left bottom) hide)
    )
    (property "Author" "Antmicro" (at 261.62 139.065 0)
      (effects (font (size 1.27 1.27) (thickness 0.15)) (justify left bottom) hide)
    )
    (property "License" "Apache-2.0" (at 261.62 141.605 0)
      (effects (font (size 1.27 1.27) (thickness 0.15)) (justify left bottom) hide)
    )
    (pin "1")
    (instances
      (project "kria-k26-devboard"
        (path ""
          (reference "#PWR0337") (unit 1)
        )
      )
    )
  )

  (symbol (lib_id "kria-k26-devboard:GND") (at 262.255 131.445 0) (mirror y) (unit 1)
    (in_bom yes) (on_board yes) (dnp no) (fields_autoplaced)
    (property "Reference" "#PWR0330" (at 262.255 137.795 0)
      (effects (font (size 1.27 1.27)) hide)
    )
    (property "Value" "GND" (at 262.255 136.525 0)
      (effects (font (size 1.27 1.27)))
    )
    (property "Footprint" "" (at 253.365 139.065 0)
      (effects (font (size 1.27 1.27) (thickness 0.15)) (justify left bottom) hide)
    )
    (property "Datasheet" "" (at 253.365 144.145 0)
      (effects (font (size 1.27 1.27) (thickness 0.15)) (justify left bottom) hide)
    )
    (property "Author" "Antmicro" (at 253.365 139.065 0)
      (effects (font (size 1.27 1.27) (thickness 0.15)) (justify left bottom) hide)
    )
    (property "License" "Apache-2.0" (at 253.365 141.605 0)
      (effects (font (size 1.27 1.27) (thickness 0.15)) (justify left bottom) hide)
    )
    (pin "1")
    (instances
      (project "kria-k26-devboard"
        (path ""
          (reference "#PWR0330") (unit 1)
        )
      )
    )
  )

  (symbol (lib_id "kria-k26-devboard:GND") (at 245.745 131.445 0) (mirror y) (unit 1)
    (in_bom yes) (on_board yes) (dnp no) (fields_autoplaced)
    (property "Reference" "#PWR0365" (at 245.745 137.795 0)
      (effects (font (size 1.27 1.27)) hide)
    )
    (property "Value" "GND" (at 245.745 136.525 0)
      (effects (font (size 1.27 1.27)))
    )
    (property "Footprint" "" (at 236.855 139.065 0)
      (effects (font (size 1.27 1.27) (thickness 0.15)) (justify left bottom) hide)
    )
    (property "Datasheet" "" (at 236.855 144.145 0)
      (effects (font (size 1.27 1.27) (thickness 0.15)) (justify left bottom) hide)
    )
    (property "Author" "Antmicro" (at 236.855 139.065 0)
      (effects (font (size 1.27 1.27) (thickness 0.15)) (justify left bottom) hide)
    )
    (property "License" "Apache-2.0" (at 236.855 141.605 0)
      (effects (font (size 1.27 1.27) (thickness 0.15)) (justify left bottom) hide)
    )
    (pin "1")
    (instances
      (project "kria-k26-devboard"
        (path ""
          (reference "#PWR0365") (unit 1)
        )
      )
    )
  )
)
